# T6G (Grand Teton) — schematic netlist excerpt (pin names and nets, part order shuffled) for the footprints in the layout excerpt that follows; sources: Cadence DE-HDL packaged netlist, KiCad conversion of 04192023_DAF0TMB3IC0_F0TG_MB_C_brd_V02_OCP.brd

R508  Q_RES  15 1% CHIP  pkg 0402LF  page 45 : A = M_I_CPU1_ALERT_N ; B = M_I_CPU1_ALERT_R_N
PC379_1  Q_CAP  22UF 16V 20% X6S  pkg C0805  page 218 : A = SW_P12V_AUX_PVDDCR_CPU1_P1_FLT ; B = GND
C635  Q_CAP  0.1UF 10V 10% X7S  pkg C0201  page 290 : A = P0V9_CPU0_RT1_2A ; B = GND

(kicad_pcb
	(version 20260206)
	(generator "pcbnew")
	(generator_version "10.0")
	(general
		(thickness 1.6)
		(legacy_teardrops no)
	)
	(paper "A4")
	(title_block
		(title "04192023_DAF0TMB3IC0_F0TG_MB_C_brd_V02_OCP.brd")
		(comment 1 "Grand Teton / footprints 8221-8223 of 8354")
	)
	(layers
		(0 "F.Cu" signal "TOP")
		(4 "In1.Cu" signal "GND")
		(6 "In2.Cu" signal "IN1")
		(8 "In3.Cu" signal "GND1")
		(10 "In4.Cu" signal "IN2")
		(12 "In5.Cu" signal "GND2")
		(14 "In6.Cu" signal "IN3")
		(16 "In7.Cu" signal "GND3")
		(18 "In8.Cu" signal "VCC")
		(20 "In9.Cu" signal "VCC1")
		(22 "In10.Cu" signal "GND4")
		(24 "In11.Cu" signal "IN4")
		(26 "In12.Cu" signal "GND5")
		(28 "In13.Cu" signal "IN5")
		(30 "In14.Cu" signal "GND6")
		(32 "In15.Cu" signal "IN6")
		(34 "In16.Cu" signal "GND7")
		(2 "B.Cu" signal "BOTTOM")
		(9 "F.Adhes" user "F.Adhesive")
		(11 "B.Adhes" user "B.Adhesive")
		(13 "F.Paste" user "Package Geometry/Pastemask Top")
		(15 "B.Paste" user "Package Geometry/Pastemask Bottom")
		(5 "F.SilkS" user "Ref Des/Silkscreen Top")
		(7 "B.SilkS" user "Ref Des/Silkscreen Bottom")
		(1 "F.Mask" user "Board Geometry/Soldermask Top")
		(3 "B.Mask" user "Board Geometry/Soldermask Bottom")
		(17 "Dwgs.User" user "User.Drawings")
		(19 "Cmts.User" user "User.Comments")
		(21 "Eco1.User" user "User.Eco1")
		(23 "Eco2.User" user "User.Eco2")
		(25 "Edge.Cuts" user "Board Geometry/Outline")
		(27 "Margin" user)
		(31 "F.CrtYd" user "Package Geometry/Place Bound Top")
		(29 "B.CrtYd" user "Package Geometry/Place Bound Bottom")
		(35 "F.Fab" user "Ref Des/Assembly Top")
		(33 "B.Fab" user "Ref Des/Assembly Bottom")
	)
	(footprint ""
		(layer "B.Cu")
		(at 338.44611 -396.393162 -90)
		(property "Reference" "C635"
			(at 0 0 90)
			(layer "B.SilkS")
			(hide yes)
			(effects
				(font
					(size 1.27 1.27)
				)
				(justify mirror)
			)
		)
		(property "Value" ""
			(at 0 0 90)
			(layer "B.Fab")
			(effects
				(font
					(size 1.27 1.27)
				)
				(justify mirror)
			)
		)
		(duplicate_pad_numbers_are_jumpers no)
		(fp_line
			(start -0.299974 0.150114)
			(end 0.299974 0.150114)
			(stroke
				(width 0.1)
				(type default)
			)
			(layer "B.Fab")
		)
		(fp_line
			(start 0.299974 0.150114)
			(end 0.299974 -0.150114)
			(stroke
				(width 0.1)
				(type default)
			)
			(layer "B.Fab")
		)
		(fp_line
			(start -0.299974 -0.150114)
			(end -0.299974 0.150114)
			(stroke
				(width 0.1)
				(type default)
			)
			(layer "B.Fab")
		)
		(fp_line
			(start 0.299974 -0.150114)
			(end -0.299974 -0.150114)
			(stroke
				(width 0.1)
				(type default)
			)
			(layer "B.Fab")
		)
		(pad "1" smd rect
			(at 0.2667 0 90)
			(size 0.3048 0.381)
			(layers "B.Cu" "B.Mask" "B.Paste")
			(net "P0V9_CPU0_RT1_2A")
		)
		(pad "2" smd rect
			(at -0.2667 0 90)
			(size 0.3048 0.381)
			(layers "B.Cu" "B.Mask" "B.Paste")
			(net "GND")
		)
	)
	(footprint ""
		(layer "B.Cu")
		(at 88.243918 -338.918042 -90)
		(property "Reference" "PC379_1"
			(at 0 0 90)
			(layer "B.SilkS")
			(hide yes)
			(effects
				(font
					(size 1.27 1.27)
				)
				(justify mirror)
			)
		)
		(property "Value" ""
			(at 0 0 90)
			(layer "B.Fab")
			(effects
				(font
					(size 1.27 1.27)
				)
				(justify mirror)
			)
		)
		(duplicate_pad_numbers_are_jumpers no)
		(fp_line
			(start -1.524 0.762)
			(end 1.524 0.762)
			(stroke
				(width 0.1524)
				(type default)
			)
			(layer "B.SilkS")
		)
		(fp_line
			(start 1.524 0.762)
			(end 1.524 -0.762)
			(stroke
				(width 0.1524)
				(type default)
			)
			(layer "B.SilkS")
		)
		(fp_line
			(start -1.524 -0.762)
			(end -1.524 0.762)
			(stroke
				(width 0.1524)
				(type default)
			)
			(layer "B.SilkS")
		)
		(fp_line
			(start 1.524 -0.762)
			(end -1.524 -0.762)
			(stroke
				(width 0.1524)
				(type default)
			)
			(layer "B.SilkS")
		)
		(fp_line
			(start -1.1049 0.724916)
			(end -1.1049 -0.724916)
			(stroke
				(width 0.1)
				(type default)
			)
			(layer "B.Fab")
		)
		(fp_line
			(start 1.1049 0.724916)
			(end -1.1049 0.724916)
			(stroke
				(width 0.1)
				(type default)
			)
			(layer "B.Fab")
		)
		(fp_line
			(start -1.1049 -0.724916)
			(end 1.1049 -0.724916)
			(stroke
				(width 0.1)
				(type default)
			)
			(layer "B.Fab")
		)
		(fp_line
			(start 1.1049 -0.724916)
			(end 1.1049 0.724916)
			(stroke
				(width 0.1)
				(type default)
			)
			(layer "B.Fab")
		)
		(pad "1" smd rect
			(at 0.889 0 270)
			(size 1.016 1.27)
			(layers "B.Cu" "B.Mask" "B.Paste")
			(net "SW_P12V_AUX_PVDDCR_CPU1_P1_FLT")
		)
		(pad "2" smd rect
			(at -0.889 0 270)
			(size 1.016 1.27)
			(layers "B.Cu" "B.Mask" "B.Paste")
			(net "GND")
		)
	)
	(footprint ""
		(layer "B.Cu")
		(at 182.619142 -244.085364)
		(property "Reference" "R508"
			(at 0 0 0)
			(layer "B.SilkS")
			(hide yes)
			(effects
				(font
					(size 1.27 1.27)
				)
				(justify mirror)
			)
		)
		(property "Value" ""
			(at 0 0 0)
			(layer "B.Fab")
			(effects
				(font
					(size 1.27 1.27)
				)
				(justify mirror)
			)
		)
		(duplicate_pad_numbers_are_jumpers no)
		(fp_line
			(start -0.7874 -0.4064)
			(end -0.7874 0.4064)
			(stroke
				(width 0.1524)
				(type default)
			)
			(layer "B.SilkS")
		)
		(fp_line
			(start -0.7874 0.4064)
			(end 0.7874 0.4064)
			(stroke
				(width 0.1524)
				(type default)
			)
			(layer "B.SilkS")
		)
		(fp_line
			(start 0.7874 -0.4064)
			(end -0.7874 -0.4064)
			(stroke
				(width 0.1524)
				(type default)
			)
			(layer "B.SilkS")
		)
		(fp_line
			(start 0.7874 0.4064)
			(end 0.7874 -0.4064)
			(stroke
				(width 0.1524)
				(type default)
			)
			(layer "B.SilkS")
		)
		(fp_line
			(start -0.67945 -0.3048)
			(end -0.67945 0.3048)
			(stroke
				(width 0.1)
				(type default)
			)
			(layer "B.Fab")
		)
		(fp_line
			(start -0.67945 0.3048)
			(end -0.120396 0.3048)
			(stroke
				(width 0.1)
				(type default)
			)
			(layer "B.Fab")
		)
		(fp_line
			(start -0.12065 -0.3048)
			(end -0.67945 -0.3048)
			(stroke
				(width 0.1)
				(type default)
			)
			(layer "B.Fab")
		)
		(fp_line
			(start -0.12065 -0.2794)
			(end -0.12065 -0.3048)
			(stroke
				(width 0.1)
				(type default)
			)
			(layer "B.Fab")
		)
		(fp_line
			(start -0.120396 0.2794)
			(end 0.12065 0.2794)
			(stroke
				(width 0.1)
				(type default)
			)
			(layer "B.Fab")
		)
		(fp_line
			(start -0.120396 0.3048)
			(end -0.120396 0.2794)
			(stroke
				(width 0.1)
				(type default)
			)
			(layer "B.Fab")
		)
		(fp_line
			(start 0.12065 -0.305054)
			(end 0.12065 -0.2794)
			(stroke
				(width 0.1)
				(type default)
			)
			(layer "B.Fab")
		)
		(fp_line
			(start 0.12065 -0.2794)
			(end -0.12065 -0.2794)
			(stroke
				(width 0.1)
				(type default)
			)
			(layer "B.Fab")
		)
		(fp_line
			(start 0.12065 0.2794)
			(end 0.12065 0.3048)
			(stroke
				(width 0.1)
				(type default)
			)
			(layer "B.Fab")
		)
		(fp_line
			(start 0.12065 0.3048)
			(end 0.67945 0.3048)
			(stroke
				(width 0.1)
				(type default)
			)
			(layer "B.Fab")
		)
		(fp_line
			(start 0.67945 -0.305054)
			(end 0.12065 -0.305054)
			(stroke
				(width 0.1)
				(type default)
			)
			(layer "B.Fab")
		)
		(fp_line
			(start 0.67945 0.3048)
			(end 0.67945 -0.305054)
			(stroke
				(width 0.1)
				(type default)
			)
			(layer "B.Fab")
		)
		(pad "1" smd circle
			(at 0.40005 0 180)
			(size 0 0)
			(layers "B.Cu" "B.Mask" "B.Paste")
			(net "M_I_CPU1_ALERT_N")
		)
		(pad "2" smd circle
			(at -0.40005 0 180)
			(size 0 0)
			(layers "B.Cu" "B.Mask" "B.Paste")
			(net "M_I_CPU1_ALERT_R_N")
		)
	)
)
